INTEGER-PLACES         5
DECIMAL-PLACES         5
X-OFFSET               0.000000
Y-OFFSET               0.000000
FEEDRATE               1
COORDINATES            ABSOLUTE
OUTPUT-UNITS           ENGLISH
TOOL-ORDER             INCREASING
REPEAT-CODES           NO
SUPPRESS-LEAD-ZEROES   NO
SUPPRESS-TRAIL-ZEROES  NO
SUPPRESS-EQUAL         NO
TOOL-SELECT            YES
OPTIMIZE_DRILLING      NO
ENHANCED_EXCELLON      NO
HEADER                 none
LEADER                 12
CODE                   ASCII
SEPARATE               NO
SEPARATE-ROUTING       NO
DRILLING               LAYER-PAIR
BACKDRILL              YES
CAVITY                 NO
COUNTER                NO
TOLERANCE_DRILL        NO
TOLERANCE_TRAVEL       NO
TOOL_SIZE              NO
ROTATION               NO
NON_STANDARD           NO
TOTAL_DRILL            NO
SEPARATE_SLOT          NO
SUPPRESS_TOLERANCE     NO
SUPPRESS_TOOLSIZE      NO
SUPPRESS_ROTATION      NO
